(kicad_pcb
	(version 20260206)
	(generator "pcbnew")
	(generator_version "10.0")
	(general
		(thickness 1.6)
		(legacy_teardrops no)
	)
	(paper "A4")
	(title_block
		(title "03242023_DA0F0TMBIJ0_F0T_Motherboard_J_brd_V01_OCP.brd")
		(comment 1 "Grand Teton / footprints 2124-2125 of 6105")
	)
	(layers
		(0 "F.Cu" signal "TOP")
		(4 "In1.Cu" signal "GND")
		(6 "In2.Cu" signal "IN1")
		(8 "In3.Cu" signal "GND1")
		(10 "In4.Cu" signal "IN2")
		(12 "In5.Cu" signal "GND2")
		(14 "In6.Cu" signal "IN3")
		(16 "In7.Cu" signal "GND3")
		(18 "In8.Cu" signal "VCC")
		(20 "In9.Cu" signal "VCC1")
		(22 "In10.Cu" signal "GND4")
		(24 "In11.Cu" signal "IN4")
		(26 "In12.Cu" signal "GND5")
		(28 "In13.Cu" signal "IN5")
		(30 "In14.Cu" signal "GND6")
		(32 "In15.Cu" signal "IN6")
		(34 "In16.Cu" signal "GND7")
		(2 "B.Cu" signal "BOTTOM")
		(9 "F.Adhes" user "F.Adhesive")
		(11 "B.Adhes" user "B.Adhesive")
		(13 "F.Paste" user "Package Geometry/Pastemask Top")
		(15 "B.Paste" user "Package Geometry/Pastemask Bottom")
		(5 "F.SilkS" user "Ref Des/Silkscreen Top")
		(7 "B.SilkS" user "Ref Des/Silkscreen Bottom")
		(1 "F.Mask" user "Board Geometry/Soldermask Top")
		(3 "B.Mask" user "Board Geometry/Soldermask Bottom")
		(17 "Dwgs.User" user "User.Drawings")
		(19 "Cmts.User" user "User.Comments")
		(21 "Eco1.User" user "User.Eco1")
		(23 "Eco2.User" user "User.Eco2")
		(25 "Edge.Cuts" user "Board Geometry/Outline")
		(27 "Margin" user)
		(31 "F.CrtYd" user "Package Geometry/Place Bound Top")
		(29 "B.CrtYd" user "Package Geometry/Place Bound Bottom")
		(35 "F.Fab" user "Ref Des/Assembly Top")
		(33 "B.Fab" user "Ref Des/Assembly Bottom")
	)
	(footprint ""
		(layer "F.Cu")
		(at 261.94258 -77.485748 -90)
		(property "Reference" "PC2279"
			(at 0 0 270)
			(layer "F.SilkS")
			(hide yes)
			(effects
				(font
					(size 1.27 1.27)
				)
			)
		)
		(property "Value" ""
			(at 0 0 270)
			(layer "F.Fab")
			(effects
				(font
					(size 1.27 1.27)
				)
			)
		)
		(duplicate_pad_numbers_are_jumpers no)
		(fp_line
			(start -0.7874 0.4064)
			(end -0.7874 -0.4064)
			(stroke
				(width 0.1524)
				(type default)
			)
			(layer "F.SilkS")
		)
		(fp_line
			(start 0.7874 0.4064)
			(end -0.7874 0.4064)
			(stroke
				(width 0.1524)
				(type default)
			)
			(layer "F.SilkS")
		)
		(fp_line
			(start -0.7874 -0.4064)
			(end 0.7874 -0.4064)
			(stroke
				(width 0.1524)
				(type default)
			)
			(layer "F.SilkS")
		)
		(fp_line
			(start 0.7874 -0.4064)
			(end 0.7874 0.4064)
			(stroke
				(width 0.1524)
				(type default)
			)
			(layer "F.SilkS")
		)
		(fp_line
			(start -0.67945 0.3048)
			(end -0.67945 -0.305054)
			(stroke
				(width 0.1)
				(type default)
			)
			(layer "F.Fab")
		)
		(fp_line
			(start -0.12065 0.3048)
			(end -0.67945 0.3048)
			(stroke
				(width 0.1)
				(type default)
			)
			(layer "F.Fab")
		)
		(fp_line
			(start 0.120396 0.3048)
			(end 0.120396 0.2794)
			(stroke
				(width 0.1)
				(type default)
			)
			(layer "F.Fab")
		)
		(fp_line
			(start 0.67945 0.3048)
			(end 0.120396 0.3048)
			(stroke
				(width 0.1)
				(type default)
			)
			(layer "F.Fab")
		)
		(fp_line
			(start -0.12065 0.2794)
			(end -0.12065 0.3048)
			(stroke
				(width 0.1)
				(type default)
			)
			(layer "F.Fab")
		)
		(fp_line
			(start 0.120396 0.2794)
			(end -0.12065 0.2794)
			(stroke
				(width 0.1)
				(type default)
			)
			(layer "F.Fab")
		)
		(fp_line
			(start -0.12065 -0.2794)
			(end 0.12065 -0.2794)
			(stroke
				(width 0.1)
				(type default)
			)
			(layer "F.Fab")
		)
		(fp_line
			(start 0.12065 -0.2794)
			(end 0.12065 -0.3048)
			(stroke
				(width 0.1)
				(type default)
			)
			(layer "F.Fab")
		)
		(fp_line
			(start 0.12065 -0.3048)
			(end 0.67945 -0.3048)
			(stroke
				(width 0.1)
				(type default)
			)
			(layer "F.Fab")
		)
		(fp_line
			(start 0.67945 -0.3048)
			(end 0.67945 0.3048)
			(stroke
				(width 0.1)
				(type default)
			)
			(layer "F.Fab")
		)
		(fp_line
			(start -0.67945 -0.305054)
			(end -0.12065 -0.305054)
			(stroke
				(width 0.1)
				(type default)
			)
			(layer "F.Fab")
		)
		(fp_line
			(start -0.12065 -0.305054)
			(end -0.12065 -0.2794)
			(stroke
				(width 0.1)
				(type default)
			)
			(layer "F.Fab")
		)
		(pad "1" smd circle
			(at -0.40005 0 270)
			(size 0 0)
			(layers "F.Cu" "F.Mask" "F.Paste")
			(net "SH_P1V05_PCH_AUX_P")
		)
		(pad "2" smd circle
			(at 0.40005 0 270)
			(size 0 0)
			(layers "F.Cu" "F.Mask" "F.Paste")
			(net "SH_P1V05_PCH_AUX_N")
		)
	)
	(footprint ""
		(layer "F.Cu")
		(at 271.312894 -64.457834 180)
		(property "Reference" "PC117"
			(at 0 0 180)
			(layer "F.SilkS")
			(hide yes)
			(effects
				(font
					(size 1.27 1.27)
				)
			)
		)
		(property "Value" ""
			(at 0 0 180)
			(layer "F.Fab")
			(effects
				(font
					(size 1.27 1.27)
				)
			)
		)
		(duplicate_pad_numbers_are_jumpers no)
		(fp_line
			(start 4.53898 2.15011)
			(end -4.53898 2.15011)
			(stroke
				(width 0.1524)
				(type default)
			)
			(layer "F.SilkS")
		)
		(fp_line
			(start 4.53898 -2.15011)
			(end 4.53898 2.15011)
			(stroke
				(width 0.1524)
				(type default)
			)
			(layer "F.SilkS")
		)
		(fp_line
			(start -4.53898 2.15011)
			(end -4.53898 -2.15011)
			(stroke
				(width 0.1524)
				(type default)
			)
			(layer "F.SilkS")
		)
		(fp_line
			(start -4.53898 -2.15011)
			(end 4.53898 -2.15011)
			(stroke
				(width 0.1524)
				(type default)
			)
			(layer "F.SilkS")
		)
		(fp_line
			(start -4.53898 -2.150618)
			(end -4.539742 2.152142)
			(stroke
				(width 0.1524)
				(type default)
			)
			(layer "F.SilkS")
		)
		(fp_line
			(start -4.69138 -2.150618)
			(end -4.692396 2.161032)
			(stroke
				(width 0.1524)
				(type default)
			)
			(layer "F.SilkS")
		)
		(fp_line
			(start -4.83108 2.150364)
			(end -4.447794 2.149348)
			(stroke
				(width 0.1524)
				(type default)
			)
			(layer "F.SilkS")
		)
		(fp_line
			(start -4.84378 -2.150618)
			(end -4.53898 -2.150618)
			(stroke
				(width 0.1524)
				(type default)
			)
			(layer "F.SilkS")
		)
		(fp_line
			(start -4.84378 -2.150618)
			(end -4.842256 2.163064)
			(stroke
				(width 0.1524)
				(type default)
			)
			(layer "F.SilkS")
		)
		(fp_line
			(start 3.64998 2.15011)
			(end -3.64998 2.15011)
			(stroke
				(width 0.1)
				(type default)
			)
			(layer "F.Fab")
		)
		(fp_line
			(start 3.64998 -2.15011)
			(end 3.64998 2.15011)
			(stroke
				(width 0.1)
				(type default)
			)
			(layer "F.Fab")
		)
		(fp_line
			(start -3.64998 2.15011)
			(end -3.64998 -2.15011)
			(stroke
				(width 0.1)
				(type default)
			)
			(layer "F.Fab")
		)
		(fp_line
			(start -3.64998 -2.15011)
			(end 3.64998 -2.15011)
			(stroke
				(width 0.1)
				(type default)
			)
			(layer "F.Fab")
		)
		(fp_text user "-"
			(at 5.788914 -0.077216 180)
			(unlocked yes)
			(layer "F.SilkS")
			(effects
				(font
					(size 1.905 1.4224)
					(thickness 0.1524)
				)
				(justify left)
			)
		)
		(fp_text user "+"
			(at -4.894326 -3.203956 180)
			(unlocked yes)
			(layer "F.SilkS")
			(effects
				(font
					(size 1.905 1.4224)
					(thickness 0.1524)
				)
				(justify left)
			)
		)
		(fp_text user "-"
			(at 4.313174 -0.094488 180)
			(unlocked yes)
			(layer "F.Fab")
			(effects
				(font
					(size 1.905 1.4224)
					(thickness 0.1524)
				)
				(justify left)
			)
		)
		(fp_text user "+"
			(at -6.214872 -0.337058 180)
			(unlocked yes)
			(layer "F.Fab")
			(effects
				(font
					(size 1.905 1.4224)
					(thickness 0.1524)
				)
				(justify left)
			)
		)
		(pad "1" smd rect
			(at -3.199892 0 180)
			(size 2.413 2.8194)
			(layers "F.Cu" "F.Mask" "F.Paste")
			(net "P1V05_PCH_AUX")
		)
		(pad "2" smd rect
			(at 3.199892 0 180)
			(size 2.413 2.8194)
			(layers "F.Cu" "F.Mask" "F.Paste")
			(net "GND")
		)
	)
)
